(kicad_pcb
	(version 20241229)
	(generator "pcbnew")
	(generator_version "9.0")
	(general
		(thickness 1.294)
		(legacy_teardrops no)
	)
	(paper "A3")
	(title_block
		(title "Kintex 410T devboard")
		(date "2024-04-03")
		(rev "1.1.2")
		(comment 9 "footprint 170 of 975 (U1), pads 416-475 of 900")
	)
	(layers
		(0 "F.Cu" mixed)
		(4 "In1.Cu" power)
		(6 "In2.Cu" power)
		(8 "In3.Cu" mixed)
		(10 "In4.Cu" power)
		(12 "In5.Cu" mixed)
		(14 "In6.Cu" power)
		(16 "In7.Cu" mixed)
		(18 "In8.Cu" power)
		(2 "B.Cu" mixed)
		(9 "F.Adhes" user "F.Adhesive")
		(11 "B.Adhes" user "B.Adhesive")
		(13 "F.Paste" user)
		(15 "B.Paste" user)
		(5 "F.SilkS" user "F.Silkscreen")
		(7 "B.SilkS" user "B.Silkscreen")
		(1 "F.Mask" user)
		(3 "B.Mask" user)
		(17 "Dwgs.User" user "User.Drawings")
		(19 "Cmts.User" user "User.Comments")
		(21 "Eco1.User" user "User.Eco1")
		(23 "Eco2.User" user "User.Eco2")
		(25 "Edge.Cuts" user)
		(27 "Margin" user)
		(31 "F.CrtYd" user "F.Courtyard")
		(29 "B.CrtYd" user "B.Courtyard")
		(35 "F.Fab" user)
		(33 "B.Fab" user)
	)
	(footprint "antmicro-footprints:BGA-900_31x31mm_Layout30x30_P1x1mm_FFG900"
		(locked yes)
		(layer "F.Cu")
		(at 200 130)
		(property "Reference" "U1"
			(at -15.74 -15.78 0)
			(layer "F.SilkS")
			(effects
				(font
					(size 0.7 0.7)
					(thickness 0.15)
				)
				(justify left bottom)
			)
		)
		(property "Value" "XC7K410T-2FFG900I"
			(at -4.436 17.635 0)
			(layer "F.Fab")
			(effects
				(font
					(size 0.7 0.7)
					(thickness 0.15)
				)
				(justify left bottom)
			)
		)
		(property "Description" "FPGA, Kintex-7, MMCM, PLL, 350 I/O's, 710 MHz, 406720 Cells, 970 mV to 1.03 V, FCBGA-900"
			(at 0 0 0)
			(layer "F.Fab")
			(hide yes)
			(effects
				(font
					(size 1.27 1.27)
					(thickness 0.15)
				)
			)
		)
		(property "Author" "Antmicro"
			(at 0 0 0)
			(layer "F.Fab")
			(hide yes)
			(effects
				(font
					(size 1 1)
					(thickness 0.15)
				)
			)
		)
		(property "License" "Apache-2.0"
			(at 0 0 0)
			(layer "F.Fab")
			(hide yes)
			(effects
				(font
					(size 1 1)
					(thickness 0.15)
				)
			)
		)
		(property "MPN" "XC7K410T-2FFG900I"
			(at 0 0 0)
			(layer "F.Fab")
			(hide yes)
			(effects
				(font
					(size 1 1)
					(thickness 0.15)
				)
			)
		)
		(property "Manufacturer" "AMD-Xilinx"
			(at 0 0 0)
			(layer "F.Fab")
			(hide yes)
			(effects
				(font
					(size 1 1)
					(thickness 0.15)
				)
			)
		)
		(sheetname "FPGA supply")
		(sheetfile "fpga-supply.kicad_sch")
		(attr smd)
		(pad "D26" smd circle
			(at 10.5 -11.5)
			(size 0.5 0.5)
			(property pad_prop_bga)
			(layers "F.Cu" "F.Mask" "F.Paste")
			(net 879 "unconnected-(U1C-IO_L11P_T1_SRCC_16-PadD26)")
			(pinfunction "IO_L11P_T1_SRCC_16")
			(pintype "bidirectional+no_connect")
			(die_length 20.509)
			(solder_mask_margin 0.02)
		)
		(pad "D27" smd circle
			(at 11.5 -11.5)
			(size 0.5 0.5)
			(property pad_prop_bga)
			(layers "F.Cu" "F.Mask" "F.Paste")
			(net 1266 "/USER_IO.B1")
			(pinfunction "IO_L13P_T2_MRCC_16")
			(pintype "bidirectional")
			(die_length 20.812)
			(solder_mask_margin 0.02)
		)
		(pad "D28" smd circle
			(at 12.5 -11.5)
			(size 0.5 0.5)
			(property pad_prop_bga)
			(layers "F.Cu" "F.Mask" "F.Paste")
			(net 1292 "/USER_IO.B32")
			(pinfunction "IO_L14N_T2_SRCC_16")
			(pintype "bidirectional")
			(die_length 21.301)
			(solder_mask_margin 0.02)
		)
		(pad "D29" smd circle
			(at 13.5 -11.5)
			(size 0.5 0.5)
			(property pad_prop_bga)
			(layers "F.Cu" "F.Mask" "F.Paste")
			(net 884 "unconnected-(U1C-IO_L16P_T2_16-PadD29)")
			(pinfunction "IO_L16P_T2_16")
			(pintype "bidirectional+no_connect")
			(die_length 22.353)
			(solder_mask_margin 0.02)
		)
		(pad "D30" smd circle
			(at 14.5 -11.5)
			(size 0.5 0.5)
			(property pad_prop_bga)
			(layers "F.Cu" "F.Mask" "F.Paste")
			(net 3 "VCC_USR_B")
			(pinfunction "VCCO_16")
			(pintype "passive")
			(solder_mask_margin 0.02)
		)
		(pad "E1" smd circle
			(at -14.5 -10.5)
			(size 0.5 0.5)
			(property pad_prop_bga)
			(layers "F.Cu" "F.Mask" "F.Paste")
			(net 1 "GND")
			(pinfunction "GND")
			(pintype "passive")
			(solder_mask_margin 0.02)
		)
		(pad "E2" smd circle
			(at -13.5 -10.5)
			(size 0.5 0.5)
			(property pad_prop_bga)
			(layers "F.Cu" "F.Mask" "F.Paste")
			(net 1 "GND")
			(pinfunction "GND")
			(pintype "passive")
			(solder_mask_margin 0.02)
		)
		(pad "E3" smd circle
			(at -12.5 -10.5)
			(size 0.5 0.5)
			(property pad_prop_bga)
			(layers "F.Cu" "F.Mask" "F.Paste")
			(net 985 "unconnected-(U1G-MGTXRXN0_118-PadE3)")
			(pinfunction "MGTXRXN0_118")
			(pintype "bidirectional+no_connect")
			(die_length 14.064)
			(solder_mask_margin 0.02)
		)
		(pad "E4" smd circle
			(at -11.5 -10.5)
			(size 0.5 0.5)
			(property pad_prop_bga)
			(layers "F.Cu" "F.Mask" "F.Paste")
			(net 986 "unconnected-(U1G-MGTXRXP0_118-PadE4)")
			(pinfunction "MGTXRXP0_118")
			(pintype "bidirectional+no_connect")
			(die_length 14.131)
			(solder_mask_margin 0.02)
		)
		(pad "E5" smd circle
			(at -10.5 -10.5)
			(size 0.5 0.5)
			(property pad_prop_bga)
			(layers "F.Cu" "F.Mask" "F.Paste")
			(net 8 "+1V2_MGTAVTT")
			(pinfunction "MGTAVTT")
			(pintype "passive")
			(solder_mask_margin 0.02)
		)
		(pad "E6" smd circle
			(at -9.5 -10.5)
			(size 0.5 0.5)
			(property pad_prop_bga)
			(layers "F.Cu" "F.Mask" "F.Paste")
			(net 1 "GND")
			(pinfunction "GND")
			(pintype "passive")
			(solder_mask_margin 0.02)
		)
		(pad "E7" smd circle
			(at -8.5 -10.5)
			(size 0.5 0.5)
			(property pad_prop_bga)
			(layers "F.Cu" "F.Mask" "F.Paste")
			(net 987 "unconnected-(U1G-MGTREFCLK1N_118-PadE7)")
			(pinfunction "MGTREFCLK1N_118")
			(pintype "bidirectional+no_connect")
			(die_length 12.062)
			(solder_mask_margin 0.02)
		)
		(pad "E8" smd circle
			(at -7.5 -10.5)
			(size 0.5 0.5)
			(property pad_prop_bga)
			(layers "F.Cu" "F.Mask" "F.Paste")
			(net 991 "unconnected-(U1G-MGTREFCLK1P_118-PadE8)")
			(pinfunction "MGTREFCLK1P_118")
			(pintype "bidirectional+no_connect")
			(die_length 11.842)
			(solder_mask_margin 0.02)
		)
		(pad "E9" smd circle
			(at -6.5 -10.5)
			(size 0.5 0.5)
			(property pad_prop_bga)
			(layers "F.Cu" "F.Mask" "F.Paste")
			(net 1 "GND")
			(pinfunction "GND")
			(pintype "passive")
			(solder_mask_margin 0.02)
		)
		(pad "E10" smd circle
			(at -5.5 -10.5)
			(size 0.5 0.5)
			(property pad_prop_bga)
			(layers "F.Cu" "F.Mask" "F.Paste")
			(net 165 "/FPGA Config/JTAG.TCK")
			(pinfunction "TCK_0")
			(pintype "bidirectional")
			(die_length 26.06)
			(solder_mask_margin 0.02)
		)
		(pad "E11" smd circle
			(at -4.5 -10.5)
			(size 0.5 0.5)
			(property pad_prop_bga)
			(layers "F.Cu" "F.Mask" "F.Paste")
			(net 268 "/FMC+ HSPC/FMC.IO16_N")
			(pinfunction "IO_L16N_T2_18")
			(pintype "bidirectional")
			(die_length 22.276)
			(solder_mask_margin 0.02)
		)
		(pad "E12" smd circle
			(at -3.5 -10.5)
			(size 0.5 0.5)
			(property pad_prop_bga)
			(layers "F.Cu" "F.Mask" "F.Paste")
			(net 1 "GND")
			(pinfunction "GND")
			(pintype "passive")
			(solder_mask_margin 0.02)
		)
		(pad "E13" smd circle
			(at -2.5 -10.5)
			(size 0.5 0.5)
			(property pad_prop_bga)
			(layers "F.Cu" "F.Mask" "F.Paste")
			(net 351 "/FMC+ HSPC/FMC.IO14_N")
			(pinfunction "IO_L14N_T2_SRCC_18")
			(pintype "bidirectional")
			(die_length 22.055)
			(solder_mask_margin 0.02)
		)
		(pad "E14" smd circle
			(at -1.5 -10.5)
			(size 0.5 0.5)
			(property pad_prop_bga)
			(layers "F.Cu" "F.Mask" "F.Paste")
			(net 337 "/FMC+ HSPC/FMC.IO20_P")
			(pinfunction "IO_L20P_T3_18")
			(pintype "bidirectional")
			(die_length 20.074)
			(solder_mask_margin 0.02)
		)
		(pad "E15" smd circle
			(at -0.5 -10.5)
			(size 0.5 0.5)
			(property pad_prop_bga)
			(layers "F.Cu" "F.Mask" "F.Paste")
			(net 335 "/FMC+ HSPC/FMC.IO20_N")
			(pinfunction "IO_L20N_T3_18")
			(pintype "bidirectional")
			(die_length 20.086)
			(solder_mask_margin 0.02)
		)
		(pad "E16" smd circle
			(at 0.5 -10.5)
			(size 0.5 0.5)
			(property pad_prop_bga)
			(layers "F.Cu" "F.Mask" "F.Paste")
			(net 409 "/FMC+ HSPC/FMC.IO19_N")
			(pinfunction "IO_L19N_T3_VREF_18")
			(pintype "bidirectional")
			(die_length 19.757)
			(solder_mask_margin 0.02)
		)
		(pad "E17" smd circle
			(at 1.5 -10.5)
			(size 0.5 0.5)
			(property pad_prop_bga)
			(layers "F.Cu" "F.Mask" "F.Paste")
			(net 24 "+3V3")
			(pinfunction "VCCO_17")
			(pintype "passive")
			(solder_mask_margin 0.02)
		)
		(pad "E18" smd circle
			(at 2.5 -10.5)
			(size 0.5 0.5)
			(property pad_prop_bga)
			(layers "F.Cu" "F.Mask" "F.Paste")
			(net 509 "/FPGA Bank 16 & 17/GBE_RGMII.RX_DV")
			(pinfunction "IO_25_17")
			(pintype "bidirectional")
			(die_length 22.737)
			(solder_mask_margin 0.02)
		)
		(pad "E19" smd circle
			(at 3.5 -10.5)
			(size 0.5 0.5)
			(property pad_prop_bga)
			(layers "F.Cu" "F.Mask" "F.Paste")
			(net 992 "unconnected-(U1C-IO_L14P_T2_SRCC_17-PadE19)")
			(pinfunction "IO_L14P_T2_SRCC_17")
			(pintype "bidirectional+no_connect")
			(die_length 20.56)
			(solder_mask_margin 0.02)
		)
		(pad "E20" smd circle
			(at 4.5 -10.5)
			(size 0.5 0.5)
			(property pad_prop_bga)
			(layers "F.Cu" "F.Mask" "F.Paste")
			(net 503 "/FPGA Bank 16 & 17/GBE_RGMII.RXD3")
			(pinfunction "IO_L12N_T1_MRCC_17")
			(pintype "bidirectional")
			(die_length 16.829)
			(solder_mask_margin 0.02)
		)
		(pad "E21" smd circle
			(at 5.5 -10.5)
			(size 0.5 0.5)
			(property pad_prop_bga)
			(layers "F.Cu" "F.Mask" "F.Paste")
			(net 993 "/FPGA Bank 16 & 17/GBE_RGMII.TXD3")
			(pinfunction "IO_L11N_T1_SRCC_17")
			(pintype "bidirectional")
			(die_length 16.731)
			(solder_mask_margin 0.02)
		)
		(pad "E22" smd circle
			(at 6.5 -10.5)
			(size 0.5 0.5)
			(property pad_prop_bga)
			(layers "F.Cu" "F.Mask" "F.Paste")
			(net 1 "GND")
			(pinfunction "GND")
			(pintype "passive")
			(solder_mask_margin 0.02)
		)
		(pad "E23" smd circle
			(at 7.5 -10.5)
			(size 0.5 0.5)
			(property pad_prop_bga)
			(layers "F.Cu" "F.Mask" "F.Paste")
			(net 933 "unconnected-(U1C-IO_L2P_T0_16-PadE23)")
			(pinfunction "IO_L2P_T0_16")
			(pintype "bidirectional+no_connect")
			(die_length 18.705)
			(solder_mask_margin 0.02)
		)
		(pad "E24" smd circle
			(at 8.5 -10.5)
			(size 0.5 0.5)
			(property pad_prop_bga)
			(layers "F.Cu" "F.Mask" "F.Paste")
			(net 935 "unconnected-(U1C-IO_L4P_T0_16-PadE24)")
			(pinfunction "IO_L4P_T0_16")
			(pintype "bidirectional+no_connect")
			(die_length 18.397)
			(solder_mask_margin 0.02)
		)
		(pad "E25" smd circle
			(at 9.5 -10.5)
			(size 0.5 0.5)
			(property pad_prop_bga)
			(layers "F.Cu" "F.Mask" "F.Paste")
			(net 936 "unconnected-(U1C-IO_L3N_T0_DQS_16-PadE25)")
			(pinfunction "IO_L3N_T0_DQS_16")
			(pintype "bidirectional+no_connect")
			(die_length 18.213)
			(solder_mask_margin 0.02)
		)
		(pad "E26" smd circle
			(at 10.5 -10.5)
			(size 0.5 0.5)
			(property pad_prop_bga)
			(layers "F.Cu" "F.Mask" "F.Paste")
			(net 937 "unconnected-(U1C-IO_L5N_T0_16-PadE26)")
			(pinfunction "IO_L5N_T0_16")
			(pintype "bidirectional+no_connect")
			(die_length 17.221)
			(solder_mask_margin 0.02)
		)
		(pad "E27" smd circle
			(at 11.5 -10.5)
			(size 0.5 0.5)
			(property pad_prop_bga)
			(layers "F.Cu" "F.Mask" "F.Paste")
			(net 3 "VCC_USR_B")
			(pinfunction "VCCO_16")
			(pintype "passive")
			(solder_mask_margin 0.02)
		)
		(pad "E28" smd circle
			(at 12.5 -10.5)
			(size 0.5 0.5)
			(property pad_prop_bga)
			(layers "F.Cu" "F.Mask" "F.Paste")
			(net 429 "/FPGA Bank 16 & 17/USR_FLASH_1.DQ0")
			(pinfunction "IO_L14P_T2_SRCC_16")
			(pintype "bidirectional")
			(die_length 20.92)
			(solder_mask_margin 0.02)
		)
		(pad "E29" smd circle
			(at 13.5 -10.5)
			(size 0.5 0.5)
			(property pad_prop_bga)
			(layers "F.Cu" "F.Mask" "F.Paste")
			(net 1270 "/USER_IO.B7")
			(pinfunction "IO_L18P_T2_16")
			(pintype "bidirectional")
			(die_length 21.495)
			(solder_mask_margin 0.02)
		)
		(pad "E30" smd circle
			(at 14.5 -10.5)
			(size 0.5 0.5)
			(property pad_prop_bga)
			(layers "F.Cu" "F.Mask" "F.Paste")
			(net 1288 "/USER_IO.B28")
			(pinfunction "IO_L18N_T2_16")
			(pintype "bidirectional")
			(die_length 21.444)
			(solder_mask_margin 0.02)
		)
		(pad "F1" smd circle
			(at -14.5 -9.5)
			(size 0.5 0.5)
			(property pad_prop_bga)
			(layers "F.Cu" "F.Mask" "F.Paste")
			(net 994 "unconnected-(U1G-MGTXTXN3_117-PadF1)")
			(pinfunction "MGTXTXN3_117")
			(pintype "bidirectional+no_connect")
			(die_length 14.68)
			(solder_mask_margin 0.02)
		)
		(pad "F2" smd circle
			(at -13.5 -9.5)
			(size 0.5 0.5)
			(property pad_prop_bga)
			(layers "F.Cu" "F.Mask" "F.Paste")
			(net 995 "unconnected-(U1G-MGTXTXP3_117-PadF2)")
			(pinfunction "MGTXTXP3_117")
			(pintype "bidirectional+no_connect")
			(die_length 14.728)
			(solder_mask_margin 0.02)
		)
		(pad "F3" smd circle
			(at -12.5 -9.5)
			(size 0.5 0.5)
			(property pad_prop_bga)
			(layers "F.Cu" "F.Mask" "F.Paste")
			(net 8 "+1V2_MGTAVTT")
			(pinfunction "MGTAVTT")
			(pintype "passive")
			(solder_mask_margin 0.02)
		)
		(pad "F4" smd circle
			(at -11.5 -9.5)
			(size 0.5 0.5)
			(property pad_prop_bga)
			(layers "F.Cu" "F.Mask" "F.Paste")
			(net 1 "GND")
			(pinfunction "GND")
			(pintype "passive")
			(solder_mask_margin 0.02)
		)
		(pad "F5" smd circle
			(at -10.5 -9.5)
			(size 0.5 0.5)
			(property pad_prop_bga)
			(layers "F.Cu" "F.Mask" "F.Paste")
			(net 999 "unconnected-(U1G-MGTXRXN3_117-PadF5)")
			(pinfunction "MGTXRXN3_117")
			(pintype "bidirectional+no_connect")
			(die_length 10.765)
			(solder_mask_margin 0.02)
		)
		(pad "F6" smd circle
			(at -9.5 -9.5)
			(size 0.5 0.5)
			(property pad_prop_bga)
			(layers "F.Cu" "F.Mask" "F.Paste")
			(net 1000 "unconnected-(U1G-MGTXRXP3_117-PadF6)")
			(pinfunction "MGTXRXP3_117")
			(pintype "bidirectional+no_connect")
			(die_length 10.959)
			(solder_mask_margin 0.02)
		)
		(pad "F7" smd circle
			(at -8.5 -9.5)
			(size 0.5 0.5)
			(property pad_prop_bga)
			(layers "F.Cu" "F.Mask" "F.Paste")
			(net 6 "+1V0_MGTAVCC")
			(pinfunction "MGTAVCC")
			(pintype "passive")
			(solder_mask_margin 0.02)
		)
		(pad "F8" smd circle
			(at -7.5 -9.5)
			(size 0.5 0.5)
			(property pad_prop_bga)
			(layers "F.Cu" "F.Mask" "F.Paste")
			(net 1 "GND")
			(pinfunction "GND")
			(pintype "passive")
			(solder_mask_margin 0.02)
		)
		(pad "F9" smd circle
			(at -6.5 -9.5)
			(size 0.5 0.5)
			(property pad_prop_bga)
			(layers "F.Cu" "F.Mask" "F.Paste")
			(net 1 "GND")
			(pinfunction "GND")
			(pintype "passive")
			(solder_mask_margin 0.02)
		)
		(pad "F10" smd circle
			(at -5.5 -9.5)
			(size 0.5 0.5)
			(property pad_prop_bga)
			(layers "F.Cu" "F.Mask" "F.Paste")
			(net 161 "/FPGA Config/JTAG.TMS")
			(pinfunction "TMS_0")
			(pintype "bidirectional")
			(die_length 26.323)
			(solder_mask_margin 0.02)
		)
		(pad "F11" smd circle
			(at -4.5 -9.5)
			(size 0.5 0.5)
			(property pad_prop_bga)
			(layers "F.Cu" "F.Mask" "F.Paste")
			(net 278 "/FMC+ HSPC/FMC.IO16_P")
			(pinfunction "IO_L16P_T2_18")
			(pintype "bidirectional")
			(die_length 22.906)
			(solder_mask_margin 0.02)
		)
		(pad "F12" smd circle
			(at -3.5 -9.5)
			(size 0.5 0.5)
			(property pad_prop_bga)
			(layers "F.Cu" "F.Mask" "F.Paste")
			(net 352 "/FMC+ HSPC/FMC.IO14_P")
			(pinfunction "IO_L14P_T2_SRCC_18")
			(pintype "bidirectional")
			(die_length 22.763)
			(solder_mask_margin 0.02)
		)
		(pad "F13" smd circle
			(at -2.5 -9.5)
			(size 0.5 0.5)
			(property pad_prop_bga)
			(layers "F.Cu" "F.Mask" "F.Paste")
			(net 353 "/FMC+ HSPC/FMC.IO12_N")
			(pinfunction "IO_L12N_T1_MRCC_18")
			(pintype "bidirectional")
			(die_length 18.979)
			(solder_mask_margin 0.02)
		)
		(pad "F14" smd circle
			(at -1.5 -9.5)
			(size 0.5 0.5)
			(property pad_prop_bga)
			(layers "F.Cu" "F.Mask" "F.Paste")
			(net 24 "+3V3")
			(pinfunction "VCCO_18")
			(pintype "passive")
			(solder_mask_margin 0.02)
		)
		(pad "F15" smd circle
			(at -0.5 -9.5)
			(size 0.5 0.5)
			(property pad_prop_bga)
			(layers "F.Cu" "F.Mask" "F.Paste")
			(net 413 "/FMC+ HSPC/FMC.IO19_P")
			(pinfunction "IO_L19P_T3_18")
			(pintype "bidirectional")
			(die_length 20.661)
			(solder_mask_margin 0.02)
		)
		(pad "F16" smd circle
			(at 0.5 -9.5)
			(size 0.5 0.5)
			(property pad_prop_bga)
			(layers "F.Cu" "F.Mask" "F.Paste")
			(net 334 "/FMC+ HSPC/FMC.IO25")
			(pinfunction "IO_25_18")
			(pintype "bidirectional")
			(die_length 20.14)
			(solder_mask_margin 0.02)
		)
		(pad "F17" smd circle
			(at 1.5 -9.5)
			(size 0.5 0.5)
			(property pad_prop_bga)
			(layers "F.Cu" "F.Mask" "F.Paste")
			(net 1001 "/FPGA Bank 16 & 17/GBE_RGMII.MDC")
			(pinfunction "IO_L18N_T2_17")
			(pintype "bidirectional")
			(die_length 21.72)
			(solder_mask_margin 0.02)
		)
		(pad "F18" smd circle
			(at 2.5 -9.5)
			(size 0.5 0.5)
			(property pad_prop_bga)
			(layers "F.Cu" "F.Mask" "F.Paste")
			(net 508 "/FPGA Bank 16 & 17/GBE_RGMII.~{INT}")
			(pinfunction "IO_L16N_T2_17")
			(pintype "bidirectional")
			(die_length 20.739)
			(solder_mask_margin 0.02)
		)
		(pad "F19" smd circle
			(at 3.5 -9.5)
			(size 0.5 0.5)
			(property pad_prop_bga)
			(layers "F.Cu" "F.Mask" "F.Paste")
			(net 1 "GND")
			(pinfunction "GND")
			(pintype "passive")
			(solder_mask_margin 0.02)
		)
		(pad "F20" smd circle
			(at 4.5 -9.5)
			(size 0.5 0.5)
			(property pad_prop_bga)
			(layers "F.Cu" "F.Mask" "F.Paste")
			(net 504 "/FPGA Bank 16 & 17/GBE_RGMII.RXD2")
			(pinfunction "IO_L12P_T1_MRCC_17")
			(pintype "bidirectional")
			(die_length 16.91)
			(solder_mask_margin 0.02)
		)
		(pad "F21" smd circle
			(at 5.5 -9.5)
			(size 0.5 0.5)
			(property pad_prop_bga)
			(layers "F.Cu" "F.Mask" "F.Paste")
			(net 1002 "/FPGA Bank 16 & 17/GBE_RGMII.TXD2")
			(pinfunction "IO_L11P_T1_SRCC_17")
			(pintype "bidirectional")
			(die_length 16.319)
			(solder_mask_margin 0.02)
		)
		(pad "F22" smd circle
			(at 6.5 -9.5)
			(size 0.5 0.5)
			(property pad_prop_bga)
			(layers "F.Cu" "F.Mask" "F.Paste")
			(net 1003 "unconnected-(U1C-IO_L9N_T1_DQS_17-PadF22)")
			(pinfunction "IO_L9N_T1_DQS_17")
			(pintype "bidirectional+no_connect")
			(die_length 13.808)
			(solder_mask_margin 0.02)
		)
		(pad "F23" smd circle
			(at 7.5 -9.5)
			(size 0.5 0.5)
			(property pad_prop_bga)
			(layers "F.Cu" "F.Mask" "F.Paste")
			(net 979 "unconnected-(U1C-IO_0_16-PadF23)")
			(pinfunction "IO_0_16")
			(pintype "bidirectional+no_connect")
			(die_length 17.681)
			(solder_mask_margin 0.02)
		)
		(pad "F24" smd circle
			(at 8.5 -9.5)
			(size 0.5 0.5)
			(property pad_prop_bga)
			(layers "F.Cu" "F.Mask" "F.Paste")
			(net 3 "VCC_USR_B")
			(pinfunction "VCCO_16")
			(pintype "passive")
			(solder_mask_margin 0.02)
		)
		(pad "F25" smd circle
			(at 9.5 -9.5)
			(size 0.5 0.5)
			(property pad_prop_bga)
			(layers "F.Cu" "F.Mask" "F.Paste")
			(net 980 "unconnected-(U1C-IO_L3P_T0_DQS_16-PadF25)")
			(pinfunction "IO_L3P_T0_DQS_16")
			(pintype "bidirectional+no_connect")
			(die_length 18.196)
			(solder_mask_margin 0.02)
		)
	)
)
